# BASEBOARD_FAB2 (Tioga Pass) — schematic netlist excerpt (pin names and nets, part order shuffled) for the footprints in the layout excerpt that follows; sources: Cadence DE-HDL packaged netlist, KiCad conversion of Wiwynn_Tioga_Pass_MB.brd

R4D68  RES  68.1K 1% EMPTY  pkg 0402  page 204 : A = VR_PVCCIN_CPU0_PH5_OCSET ; B = GND

(kicad_pcb
	(version 20260206)
	(generator "pcbnew")
	(generator_version "10.0")
	(general
		(thickness 1.6)
		(legacy_teardrops no)
	)
	(paper "A4")
	(title_block
		(title "Wiwynn_Tioga_Pass_MB.brd")
		(comment 1 "Tioga Pass / footprints 859-859 of 4770")
	)
	(layers
		(0 "F.Cu" signal "TOP")
		(4 "In1.Cu" signal "L2GND")
		(6 "In2.Cu" signal "L3")
		(8 "In3.Cu" signal "L4GND")
		(10 "In4.Cu" signal "L5")
		(12 "In5.Cu" signal "L6GND")
		(14 "In6.Cu" signal "L7VCC")
		(16 "In7.Cu" signal "L8VCC")
		(18 "In8.Cu" signal "L9GND")
		(20 "In9.Cu" signal "L10")
		(22 "In10.Cu" signal "L11GND")
		(24 "In11.Cu" signal "L12")
		(26 "In12.Cu" signal "L13GND")
		(2 "B.Cu" signal "BOTTOM")
		(9 "F.Adhes" user "F.Adhesive")
		(11 "B.Adhes" user "B.Adhesive")
		(13 "F.Paste" user "Package Geometry/Pastemask Top")
		(15 "B.Paste" user "Package Geometry/Pastemask Bottom")
		(5 "F.SilkS" user "Ref Des/Silkscreen Top")
		(7 "B.SilkS" user "Ref Des/Silkscreen Bottom")
		(1 "F.Mask" user "Board Geometry/Soldermask Top")
		(3 "B.Mask" user "Board Geometry/Soldermask Bottom")
		(17 "Dwgs.User" user "User.Drawings")
		(19 "Cmts.User" user "User.Comments")
		(21 "Eco1.User" user "User.Eco1")
		(23 "Eco2.User" user "User.Eco2")
		(25 "Edge.Cuts" user "Board Geometry/Outline")
		(27 "Margin" user)
		(31 "F.CrtYd" user "Package Geometry/Place Bound Top")
		(29 "B.CrtYd" user "Package Geometry/Place Bound Bottom")
		(35 "F.Fab" user "Ref Des/Assembly Top")
		(33 "B.Fab" user "Ref Des/Assembly Bottom")
	)
	(footprint ""
		(layer "F.Cu")
		(at 193.6369 -88.19642)
		(property "Reference" "R4D68"
			(at 0 0 0)
			(layer "F.SilkS")
			(hide yes)
			(effects
				(font
					(size 1.27 1.27)
				)
			)
		)
		(property "Value" ""
			(at 0 0 0)
			(layer "F.Fab")
			(effects
				(font
					(size 1.27 1.27)
				)
			)
		)
		(duplicate_pad_numbers_are_jumpers no)
		(fp_poly
			(pts
				(xy -0.2794 -0.1016) (xy 0.2794 -0.1016) (xy 0.2794 0.9906) (xy -0.2794 0.9906)
			)
			(stroke
				(width 0)
				(type default)
			)
			(fill no)
			(layer "F.CrtYd")
		)
		(fp_line
			(start -0.2794 -0.1016)
			(end -0.2794 0.9906)
			(stroke
				(width 0.1)
				(type default)
			)
			(layer "F.Fab")
		)
		(fp_line
			(start -0.2794 0.9906)
			(end 0.2794 0.9906)
			(stroke
				(width 0.1)
				(type default)
			)
			(layer "F.Fab")
		)
		(fp_line
			(start 0.2794 -0.1016)
			(end -0.2794 -0.1016)
			(stroke
				(width 0.1)
				(type default)
			)
			(layer "F.Fab")
		)
		(fp_line
			(start 0.2794 0.9906)
			(end 0.2794 -0.1016)
			(stroke
				(width 0.1)
				(type default)
			)
			(layer "F.Fab")
		)
		(pad "1" smd rect
			(at 0 0)
			(size 0.508 0.508)
			(layers "F.Cu" "F.Mask" "F.Paste")
			(net "VR_PVCCIN_CPU0_PH5_OCSET")
		)
		(pad "2" smd rect
			(at 0 0.889)
			(size 0.508 0.508)
			(layers "F.Cu" "F.Mask" "F.Paste")
			(net "GND")
		)
		(zone
			(layer "F.Cu")
			(hatch none 0.5)
			(connect_pads
				(clearance 0)
			)
			(min_thickness 0.25)
			(keepout
				(tracks allowed)
				(vias not_allowed)
				(pads allowed)
				(copperpour not_allowed)
				(footprints allowed)
			)
			(placement
				(enabled no)
				(sheetname "")
			)
			(fill
				(thermal_gap 0.5)
				(thermal_bridge_width 0.5)
				(island_removal_mode 0)
			)
			(polygon
				(pts
					(xy 193.3829 -87.94242) (xy 193.8909 -87.94242) (xy 193.8909 -87.56142) (xy 193.3829 -87.56142)
				)
			)
		)
		(zone
			(layer "F.Cu")
			(hatch none 0.5)
			(connect_pads
				(clearance 0)
			)
			(min_thickness 0.25)
			(keepout
				(tracks not_allowed)
				(vias allowed)
				(pads allowed)
				(copperpour not_allowed)
				(footprints allowed)
			)
			(placement
				(enabled no)
				(sheetname "")
			)
			(fill
				(thermal_gap 0.5)
				(thermal_bridge_width 0.5)
				(island_removal_mode 0)
			)
			(polygon
				(pts
					(xy 193.3829 -87.56142) (xy 193.8909 -87.56142) (xy 193.8909 -87.94242) (xy 193.3829 -87.94242)
				)
			)
		)
	)
)
